(kicad_pcb
	(version 20241229)
	(generator "pcbnew")
	(generator_version "9.0")
	(general
		(thickness 1.711)
		(legacy_teardrops no)
	)
	(paper "A4")
	(title_block
		(title "Antmicro Baseboard for Jetson AGX Thor")
		(date "2026-02-18")
		(rev "1.1.0")
		(company "Antmicro Ltd")
		(comment 1 "www.antmicro.com")
		(comment 9 "footprint 270 of 1170 (U30), pads 1-68 of 78")
	)
	(layers
		(0 "F.Cu" signal)
		(4 "In1.Cu" signal)
		(6 "In2.Cu" signal)
		(8 "In3.Cu" signal)
		(10 "In4.Cu" jumper)
		(12 "In5.Cu" signal)
		(14 "In6.Cu" signal)
		(16 "In7.Cu" signal)
		(18 "In8.Cu" signal)
		(2 "B.Cu" signal)
		(9 "F.Adhes" user "F.Adhesive")
		(11 "B.Adhes" user "B.Adhesive")
		(13 "F.Paste" user)
		(15 "B.Paste" user)
		(5 "F.SilkS" user "F.Silkscreen")
		(7 "B.SilkS" user "B.Silkscreen")
		(1 "F.Mask" user)
		(3 "B.Mask" user)
		(17 "Dwgs.User" user "User.Drawings")
		(19 "Cmts.User" user "User.Comments")
		(21 "Eco1.User" user "User.Eco1")
		(23 "Eco2.User" user "User.Eco2")
		(25 "Edge.Cuts" user)
		(27 "Margin" user)
		(31 "F.CrtYd" user "F.Courtyard")
		(29 "B.CrtYd" user "B.Courtyard")
		(35 "F.Fab" user)
		(33 "B.Fab" user)
	)
	(footprint "antmicro-footprints:IC_TPS65987DDHRSHR"
		(layer "F.Cu")
		(at 200.599 78.48 180)
		(property "Reference" "U30"
			(at -4.801 4.98 180)
			(layer "F.SilkS")
			(effects
				(font
					(size 0.7 0.7)
					(thickness 0.15)
				)
				(justify right top)
			)
		)
		(property "Value" "TPS65988DHRSHR"
			(at 0 4.9 0)
			(layer "F.Fab")
			(effects
				(font
					(size 0.7 0.7)
					(thickness 0.15)
				)
				(justify right top)
			)
		)
		(property "Datasheet" "https://www.ti.com/lit/ds/symlink/tps65988.pdf?ts=1662726631004&ref_url=https%253A%252F%252Fwww.ti.com%252Fproduct%252FTPS65988"
			(at 0 0 0)
			(layer "F.Fab")
			(hide yes)
			(effects
				(font
					(size 1.27 1.27)
					(thickness 0.15)
				)
			)
		)
		(property "Description" "USB, Type-C Controller PMIC 56-VQFN (7x7)"
			(at 0 0 0)
			(layer "F.Fab")
			(hide yes)
			(effects
				(font
					(size 1.27 1.27)
					(thickness 0.15)
				)
			)
		)
		(property "MPN" "TPS65988DHRSHR "
			(at 0 0 180)
			(unlocked yes)
			(layer "F.Fab")
			(hide yes)
			(effects
				(font
					(size 1 1)
					(thickness 0.15)
				)
			)
		)
		(property "Manufacturer" "Texas Instruments"
			(at 0 0 180)
			(unlocked yes)
			(layer "F.Fab")
			(hide yes)
			(effects
				(font
					(size 1 1)
					(thickness 0.15)
				)
			)
		)
		(property "License" "Apache-2.0"
			(at 0 0 180)
			(unlocked yes)
			(layer "F.Fab")
			(hide yes)
			(effects
				(font
					(size 1 1)
					(thickness 0.15)
				)
			)
		)
		(property "Author" "Antmicro"
			(at 0 0 180)
			(unlocked yes)
			(layer "F.Fab")
			(hide yes)
			(effects
				(font
					(size 1 1)
					(thickness 0.15)
				)
			)
		)
		(sheetname "/USB DP Alt mode/")
		(sheetfile "usb_dp.kicad_sch")
		(attr smd)
		(pad "1" smd roundrect
			(at -3.351 -2.4 180)
			(size 0.8 0.65)
			(layers "F.Cu")
			(roundrect_rratio 0.09)
			(net 522 "/Power/USBPD1_HV")
			(pinfunction "PP_HV2")
			(pintype "bidirectional")
		)
		(pad "3" smd roundrect
			(at -3.351 -1.601 180)
			(size 0.8 0.65)
			(layers "F.Cu")
			(roundrect_rratio 0.09)
			(net 376 "/USB DP Alt mode/USBC1_VBUS")
			(pinfunction "VBUS2")
			(pintype "bidirectional")
		)
		(pad "5" smd roundrect
			(at -3.351 -1 180)
			(size 0.7 0.2)
			(layers "F.Cu" "F.Mask" "F.Paste")
			(roundrect_rratio 0.25)
			(net 2 "+3V3")
			(pinfunction "VIN_3V3")
			(pintype "power_in")
		)
		(pad "6" smd roundrect
			(at -3.351 -0.6 180)
			(size 0.7 0.2)
			(layers "F.Cu" "F.Mask" "F.Paste")
			(roundrect_rratio 0.25)
			(net 934 "/USB Debug, PD/PDC_ADCIN1")
			(pinfunction "ADCIN1")
			(pintype "input")
		)
		(pad "7" smd roundrect
			(at -3.351 -0.202 180)
			(size 0.7 0.2)
			(layers "F.Cu" "F.Mask" "F.Paste")
			(roundrect_rratio 0.25)
			(net 1149 "unconnected-(U30C-DRAIN2-Pad52)_2")
			(pinfunction "DRAIN2")
			(pintype "passive+no_connect")
		)
		(pad "8" smd roundrect
			(at -3.351 0.2 180)
			(size 0.7 0.2)
			(layers "F.Cu" "F.Mask" "F.Paste")
			(roundrect_rratio 0.25)
			(net 1145 "unconnected-(U30B-DRAIN1-Pad15)_3")
			(pinfunction "DRAIN1")
			(pintype "passive+no_connect")
		)
		(pad "9" smd roundrect
			(at -3.351 0.598 180)
			(size 0.7 0.2)
			(layers "F.Cu" "F.Mask" "F.Paste")
			(roundrect_rratio 0.25)
			(net 294 "/USB Debug, PD/PDC_LDO_3V3")
			(pinfunction "LDO_3V3")
			(pintype "power_out")
		)
		(pad "10" smd roundrect
			(at -3.351 0.998 180)
			(size 0.7 0.2)
			(layers "F.Cu" "F.Mask" "F.Paste")
			(roundrect_rratio 0.25)
			(net 935 "/USB Debug, PD/PDC_ADCIN2")
			(pinfunction "ADCIN2")
			(pintype "input")
		)
		(pad "11" smd roundrect
			(at -3.351 1.6 180)
			(size 0.8 0.65)
			(layers "F.Cu")
			(roundrect_rratio 0.09)
			(net 525 "/Power/USBPD2_HV")
			(pinfunction "PP_HV1")
			(pintype "bidirectional")
		)
		(pad "13" smd roundrect
			(at -3.351 2.398 180)
			(size 0.8 0.65)
			(layers "F.Cu")
			(roundrect_rratio 0.09)
			(net 176 "/USB Debug, PD/USBC0_VBUS")
			(pinfunction "VBUS1")
			(pintype "bidirectional")
		)
		(pad "15" smd roundrect
			(at -2.601 3.35 270)
			(size 0.7 0.2)
			(layers "F.Cu" "F.Mask" "F.Paste")
			(roundrect_rratio 0.25)
			(net 1157 "unconnected-(U30B-DRAIN1-Pad15)_8")
			(pinfunction "DRAIN1")
			(pintype "passive+no_connect")
		)
		(pad "16" smd roundrect
			(at -2.202 3.35 270)
			(size 0.7 0.2)
			(layers "F.Cu" "F.Mask" "F.Paste")
			(roundrect_rratio 0.25)
			(net 942 "/USB DP Alt mode/USBC1_FLIP")
			(pinfunction "GPIO0")
			(pintype "bidirectional")
		)
		(pad "17" smd roundrect
			(at -1.801 3.35 270)
			(size 0.7 0.2)
			(layers "F.Cu" "F.Mask" "F.Paste")
			(roundrect_rratio 0.25)
			(net 943 "/USB DP Alt mode/USBC1_CTL0")
			(pinfunction "GPIO1")
			(pintype "bidirectional")
		)
		(pad "18" smd roundrect
			(at -1.401 3.35 270)
			(size 0.7 0.2)
			(layers "F.Cu" "F.Mask" "F.Paste")
			(roundrect_rratio 0.25)
			(net 944 "/USB DP Alt mode/USBC1_CTL1")
			(pinfunction "GPIO2")
			(pintype "bidirectional")
		)
		(pad "19" smd roundrect
			(at -1 3.35 270)
			(size 0.7 0.2)
			(layers "F.Cu" "F.Mask" "F.Paste")
			(roundrect_rratio 0.25)
			(net 1144 "unconnected-(U30B-DRAIN1-Pad15)_2")
			(pinfunction "DRAIN1")
			(pintype "passive+no_connect")
		)
		(pad "20" smd roundrect
			(at -0.6 3.35 270)
			(size 0.7 0.2)
			(layers "F.Cu" "F.Mask" "F.Paste")
			(roundrect_rratio 0.25)
			(net 1 "GND")
			(pinfunction "GND")
			(pintype "power_in")
		)
		(pad "21" smd roundrect
			(at -0.202 3.35 270)
			(size 0.7 0.2)
			(layers "F.Cu" "F.Mask" "F.Paste")
			(roundrect_rratio 0.25)
			(net 1039 "/USB Debug, PD/PDC_I2C3_SCL")
			(pinfunction "I2C3_SCL")
			(pintype "bidirectional")
		)
		(pad "22" smd roundrect
			(at 0.2 3.35 270)
			(size 0.7 0.2)
			(layers "F.Cu" "F.Mask" "F.Paste")
			(roundrect_rratio 0.25)
			(net 1040 "/USB Debug, PD/PDC_I2C3_SDA")
			(pinfunction "I2C3_SDA")
			(pintype "bidirectional")
		)
		(pad "23" smd roundrect
			(at 0.598 3.35 270)
			(size 0.7 0.2)
			(layers "F.Cu" "F.Mask" "F.Paste")
			(roundrect_rratio 0.25)
			(net 1041 "/USB Debug, PD/~{PDC_I2C3_IRQ}")
			(pinfunction "~{I2C3_IRQ}")
			(pintype "bidirectional")
		)
		(pad "24" smd roundrect
			(at 0.998 3.35 270)
			(size 0.7 0.2)
			(layers "F.Cu" "F.Mask" "F.Paste")
			(roundrect_rratio 0.25)
			(net 514 "/USB Debug, PD/USBC0_CC1")
			(pinfunction "C1_CC1")
			(pintype "bidirectional")
		)
		(pad "25" smd roundrect
			(at 1.398 3.35 270)
			(size 0.7 0.2)
			(layers "F.Cu" "F.Mask" "F.Paste")
			(roundrect_rratio 0.25)
			(net 5 "+5V")
			(pinfunction "PP1_CABLE")
			(pintype "power_in")
		)
		(pad "26" smd roundrect
			(at 1.8 3.35 270)
			(size 0.7 0.2)
			(layers "F.Cu" "F.Mask" "F.Paste")
			(roundrect_rratio 0.25)
			(net 515 "/USB Debug, PD/USBC0_CC2")
			(pinfunction "C1_CC2")
			(pintype "bidirectional")
		)
		(pad "27" smd roundrect
			(at 2.2 3.35 270)
			(size 0.7 0.2)
			(layers "F.Cu" "F.Mask" "F.Paste")
			(roundrect_rratio 0.25)
			(net 945 "/USB Debug, PD/DEBUG_SCL")
			(pinfunction "I2C1_SCL")
			(pintype "bidirectional")
		)
		(pad "28" smd roundrect
			(at 2.6 3.35 270)
			(size 0.7 0.2)
			(layers "F.Cu" "F.Mask" "F.Paste")
			(roundrect_rratio 0.25)
			(net 946 "/USB Debug, PD/DEBUG_SDA")
			(pinfunction "I2C1_SDA")
			(pintype "bidirectional")
		)
		(pad "29" smd roundrect
			(at 3.35 2.6 180)
			(size 0.7 0.2)
			(layers "F.Cu" "F.Mask" "F.Paste")
			(roundrect_rratio 0.25)
			(net 953 "/USB Debug, PD/PDC_I2C1_IRQn")
			(pinfunction "~{I2C1_IRQ}")
			(pintype "output")
		)
		(pad "30" smd roundrect
			(at 3.35 2.2 180)
			(size 0.7 0.2)
			(layers "F.Cu" "F.Mask" "F.Paste")
			(roundrect_rratio 0.25)
			(net 1168 "Net-(U30A-HPD1)")
			(pinfunction "HPD1")
			(pintype "bidirectional")
		)
		(pad "31" smd roundrect
			(at 3.35 1.8 180)
			(size 0.7 0.2)
			(layers "F.Cu" "F.Mask" "F.Paste")
			(roundrect_rratio 0.25)
			(net 949 "/USB Debug, PD/PDC_HPD2")
			(pinfunction "HPD2")
			(pintype "bidirectional")
		)
		(pad "32" smd roundrect
			(at 3.35 1.398 180)
			(size 0.7 0.2)
			(layers "F.Cu" "F.Mask" "F.Paste")
			(roundrect_rratio 0.25)
			(net 947 "/USB Debug, PD/PDC_I2C2_SCL")
			(pinfunction "I2C2_SCL")
			(pintype "bidirectional")
		)
		(pad "33" smd roundrect
			(at 3.35 0.998 180)
			(size 0.7 0.2)
			(layers "F.Cu" "F.Mask" "F.Paste")
			(roundrect_rratio 0.25)
			(net 950 "/USB Debug, PD/PDC_I2C2_SDA")
			(pinfunction "I2C2_SDA")
			(pintype "bidirectional")
		)
		(pad "34" smd roundrect
			(at 3.35 0.598 180)
			(size 0.7 0.2)
			(layers "F.Cu" "F.Mask" "F.Paste")
			(roundrect_rratio 0.25)
			(net 1042 "/USB Debug, PD/PDC_I2C2_IRQn")
			(pinfunction "~{I2C2_IRQ}")
			(pintype "output")
		)
		(pad "35" smd roundrect
			(at 3.35 0.2 180)
			(size 0.7 0.2)
			(layers "F.Cu" "F.Mask" "F.Paste")
			(roundrect_rratio 0.25)
			(net 293 "/USB Debug, PD/PDC_LDO_1V8")
			(pinfunction "LDO_1V8")
			(pintype "power_out")
		)
		(pad "36" smd roundrect
			(at 3.35 -0.202 180)
			(size 0.7 0.2)
			(layers "F.Cu" "F.Mask" "F.Paste")
			(roundrect_rratio 0.25)
			(net 936 "/USB Debug, PD/PDC_MISO")
			(pinfunction "SPI_POCI")
			(pintype "bidirectional")
		)
		(pad "37" smd roundrect
			(at 3.35 -0.6 180)
			(size 0.7 0.2)
			(layers "F.Cu" "F.Mask" "F.Paste")
			(roundrect_rratio 0.25)
			(net 940 "/USB Debug, PD/PDC_MOSI")
			(pinfunction "SPI_PICO")
			(pintype "bidirectional")
		)
		(pad "38" smd roundrect
			(at 3.35 -1 180)
			(size 0.7 0.2)
			(layers "F.Cu" "F.Mask" "F.Paste")
			(roundrect_rratio 0.25)
			(net 941 "/USB Debug, PD/PDC_SCLK")
			(pinfunction "SPI_CLK")
			(pintype "bidirectional")
		)
		(pad "39" smd roundrect
			(at 3.35 -1.401 180)
			(size 0.7 0.2)
			(layers "F.Cu" "F.Mask" "F.Paste")
			(roundrect_rratio 0.25)
			(net 939 "/USB Debug, PD/~{PDC_CS}")
			(pinfunction "~{SPI_CS}")
			(pintype "bidirectional")
		)
		(pad "40" smd roundrect
			(at 3.35 -1.801 180)
			(size 0.7 0.2)
			(layers "F.Cu" "F.Mask" "F.Paste")
			(roundrect_rratio 0.25)
			(net 1109 "unconnected-(U30A-GPIO12-Pad40)")
			(pinfunction "GPIO12")
			(pintype "bidirectional+no_connect")
		)
		(pad "41" smd roundrect
			(at 3.35 -2.202 180)
			(size 0.7 0.2)
			(layers "F.Cu" "F.Mask" "F.Paste")
			(roundrect_rratio 0.25)
			(net 1110 "unconnected-(U30A-GPIO13-Pad41)")
			(pinfunction "GPIO13")
			(pintype "bidirectional+no_connect")
		)
		(pad "42" smd roundrect
			(at 3.35 -2.601 180)
			(size 0.7 0.2)
			(layers "F.Cu" "F.Mask" "F.Paste")
			(roundrect_rratio 0.25)
			(net 951 "/USB Debug, PD/PDC_GPIO14")
			(pinfunction "PWM1")
			(pintype "bidirectional")
		)
		(pad "43" smd roundrect
			(at 2.6 -3.351 270)
			(size 0.7 0.2)
			(layers "F.Cu" "F.Mask" "F.Paste")
			(roundrect_rratio 0.25)
			(net 952 "/USB Debug, PD/PDC_GPIO15")
			(pinfunction "PWM2")
			(pintype "bidirectional")
		)
		(pad "44" smd roundrect
			(at 2.2 -3.351 270)
			(size 0.7 0.2)
			(layers "F.Cu" "F.Mask" "F.Paste")
			(roundrect_rratio 0.25)
			(net 933 "/USB Debug, PD/PDC_RESET")
			(pinfunction "HRESET")
			(pintype "input")
		)
		(pad "45" smd roundrect
			(at 1.8 -3.351 270)
			(size 0.7 0.2)
			(layers "F.Cu" "F.Mask" "F.Paste")
			(roundrect_rratio 0.25)
			(net 817 "/USB DP Alt mode/USBC1_CC1")
			(pinfunction "C2_CC1")
			(pintype "bidirectional")
		)
		(pad "46" smd roundrect
			(at 1.398 -3.351 270)
			(size 0.7 0.2)
			(layers "F.Cu" "F.Mask" "F.Paste")
			(roundrect_rratio 0.25)
			(net 5 "+5V")
			(pinfunction "PP2_CABLE")
			(pintype "power_in")
		)
		(pad "47" smd roundrect
			(at 0.998 -3.351 270)
			(size 0.7 0.2)
			(layers "F.Cu" "F.Mask" "F.Paste")
			(roundrect_rratio 0.25)
			(net 816 "/USB DP Alt mode/USBC1_CC2")
			(pinfunction "C2_CC2")
			(pintype "bidirectional")
		)
		(pad "48" smd roundrect
			(at 0.598 -3.351 270)
			(size 0.7 0.2)
			(layers "F.Cu" "F.Mask" "F.Paste")
			(roundrect_rratio 0.25)
			(net 975 "/USB Debug, PD/USBC0_5V_PEN")
			(pinfunction "PP_EXT1")
			(pintype "bidirectional")
		)
		(pad "49" smd roundrect
			(at 0.2 -3.351 270)
			(size 0.7 0.2)
			(layers "F.Cu" "F.Mask" "F.Paste")
			(roundrect_rratio 0.25)
			(net 970 "/USB DP Alt mode/USBC1_5V_PEN")
			(pinfunction "PP_EXT2")
			(pintype "bidirectional")
		)
		(pad "50" smd roundrect
			(at -0.202 -3.351 270)
			(size 0.7 0.2)
			(layers "F.Cu" "F.Mask" "F.Paste")
			(roundrect_rratio 0.25)
			(net 1176 "unconnected-(U30B-C1_USB_P-Pad50)")
			(pinfunction "C1_USB_P")
			(pintype "bidirectional+no_connect")
		)
		(pad "51" smd roundrect
			(at -0.6 -3.351 270)
			(size 0.7 0.2)
			(layers "F.Cu" "F.Mask" "F.Paste")
			(roundrect_rratio 0.25)
			(net 1 "GND")
			(pinfunction "GND")
			(pintype "passive")
		)
		(pad "52" smd roundrect
			(at -1 -3.351 270)
			(size 0.7 0.2)
			(layers "F.Cu" "F.Mask" "F.Paste")
			(roundrect_rratio 0.25)
			(net 1148 "unconnected-(U30C-DRAIN2-Pad52)_1")
			(pinfunction "DRAIN2")
			(pintype "passive+no_connect")
		)
		(pad "53" smd roundrect
			(at -1.401 -3.351 270)
			(size 0.7 0.2)
			(layers "F.Cu" "F.Mask" "F.Paste")
			(roundrect_rratio 0.25)
			(net 1178 "unconnected-(U30B-C1_USB_N-Pad53)")
			(pinfunction "C1_USB_N")
			(pintype "bidirectional+no_connect")
		)
		(pad "54" smd roundrect
			(at -1.801 -3.351 270)
			(size 0.7 0.2)
			(layers "F.Cu" "F.Mask" "F.Paste")
			(roundrect_rratio 0.25)
			(net 1177 "unconnected-(U30C-C2_USB_P-Pad54)")
			(pinfunction "C2_USB_P")
			(pintype "bidirectional+no_connect")
		)
		(pad "55" smd roundrect
			(at -2.202 -3.351 270)
			(size 0.7 0.2)
			(layers "F.Cu" "F.Mask" "F.Paste")
			(roundrect_rratio 0.25)
			(net 1179 "unconnected-(U30C-C2_USB_N-Pad55)")
			(pinfunction "C2_USB_N")
			(pintype "bidirectional+no_connect")
		)
		(pad "56" smd roundrect
			(at -2.601 -3.351 270)
			(size 0.7 0.2)
			(layers "F.Cu" "F.Mask" "F.Paste")
			(roundrect_rratio 0.25)
			(net 1139 "unconnected-(U30C-DRAIN2-Pad52)")
			(pinfunction "DRAIN2")
			(pintype "passive+no_connect")
		)
		(pad "57" thru_hole circle
			(at -2.351 -2.327 180)
			(size 0.45 0.45)
			(drill 0.1)
			(layers "*.Cu")
			(remove_unused_layers no)
			(net 1152 "unconnected-(U30C-DRAIN2-Pad52)_5")
			(pinfunction "DRAIN2")
			(pintype "passive+no_connect")
		)
		(pad "57" thru_hole circle
			(at -2.351 -1.45 180)
			(size 0.45 0.45)
			(drill 0.1)
			(layers "*.Cu")
			(remove_unused_layers no)
			(net 1150 "unconnected-(U30C-DRAIN2-Pad52)_3")
			(pinfunction "DRAIN2")
			(pintype "passive+no_connect")
		)
		(pad "57" thru_hole circle
			(at -2.351 -0.576 180)
			(size 0.45 0.45)
			(drill 0.1)
			(layers "*.Cu")
			(remove_unused_layers no)
			(net 1154 "unconnected-(U30C-DRAIN2-Pad52)_7")
			(pinfunction "DRAIN2")
			(pintype "passive+no_connect")
		)
		(pad "57" smd roundrect
			(at -1.875 -1.45 270)
			(size 2.6 1.75)
			(layers "F.Cu" "F.Mask")
			(roundrect_rratio 0.05714285714)
			(net 1151 "unconnected-(U30C-DRAIN2-Pad52)_4")
			(pinfunction "DRAIN2")
			(pintype "passive+no_connect")
			(solder_mask_margin 0.05)
		)
		(pad "57" thru_hole circle
			(at -1.401 -2.327 180)
			(size 0.45 0.45)
			(drill 0.1)
			(layers "*.Cu")
			(remove_unused_layers no)
			(net 1159 "unconnected-(U30C-DRAIN2-Pad52)_8")
			(pinfunction "DRAIN2")
			(pintype "passive+no_connect")
		)
		(pad "57" thru_hole circle
			(at -1.401 -1.45 180)
			(size 0.45 0.45)
			(drill 0.1)
			(layers "*.Cu")
			(remove_unused_layers no)
			(net 1153 "unconnected-(U30C-DRAIN2-Pad52)_6")
			(pinfunction "DRAIN2")
			(pintype "passive+no_connect")
		)
		(pad "57" thru_hole circle
			(at -1.401 -0.577 180)
			(size 0.45 0.45)
			(drill 0.1)
			(layers "*.Cu")
			(remove_unused_layers no)
			(net 1160 "unconnected-(U30C-DRAIN2-Pad52)_9")
			(pinfunction "DRAIN2")
			(pintype "passive+no_connect")
		)
		(pad "58" thru_hole circle
			(at -2.351 0.598 180)
			(size 0.45 0.45)
			(drill 0.1)
			(layers "*.Cu")
			(remove_unused_layers no)
			(net 1140 "unconnected-(U30B-DRAIN1-Pad15)")
			(pinfunction "DRAIN1")
			(pintype "passive+no_connect")
		)
		(pad "58" thru_hole circle
			(at -2.351 1.475 180)
			(size 0.45 0.45)
			(drill 0.1)
			(layers "*.Cu")
			(remove_unused_layers no)
			(net 1143 "unconnected-(U30B-DRAIN1-Pad15)_1")
			(pinfunction "DRAIN1")
			(pintype "passive+no_connect")
		)
		(pad "58" thru_hole circle
			(at -2.351 2.35 180)
			(size 0.45 0.45)
			(drill 0.1)
			(layers "*.Cu")
			(remove_unused_layers no)
			(net 1147 "unconnected-(U30B-DRAIN1-Pad15)_5")
			(pinfunction "DRAIN1")
			(pintype "passive+no_connect")
		)
		(pad "58" smd roundrect
			(at -1.875 1.475 270)
			(size 2.55 1.75)
			(layers "F.Cu" "F.Mask")
			(roundrect_rratio 0.05714285714)
			(net 1156 "unconnected-(U30B-DRAIN1-Pad15)_7")
			(pinfunction "DRAIN1")
			(pintype "passive+no_connect")
			(solder_mask_margin 0.05)
		)
		(pad "58" thru_hole circle
			(at -1.401 0.598 180)
			(size 0.45 0.45)
			(drill 0.1)
			(layers "*.Cu")
			(remove_unused_layers no)
			(net 1146 "unconnected-(U30B-DRAIN1-Pad15)_4")
			(pinfunction "DRAIN1")
			(pintype "passive+no_connect")
		)
		(pad "58" thru_hole circle
			(at -1.401 1.475 180)
			(size 0.45 0.45)
			(drill 0.1)
			(layers "*.Cu")
			(remove_unused_layers no)
			(net 1155 "unconnected-(U30B-DRAIN1-Pad15)_6")
			(pinfunction "DRAIN1")
			(pintype "passive+no_connect")
		)
		(pad "58" thru_hole circle
			(at -1.401 2.349 180)
			(size 0.45 0.45)
			(drill 0.1)
			(layers "*.Cu")
			(remove_unused_layers no)
			(net 1158 "unconnected-(U30B-DRAIN1-Pad15)_9")
			(pinfunction "DRAIN1")
			(pintype "passive+no_connect")
		)
		(pad "59" thru_hole circle
			(at -0.152 1.322 180)
			(size 0.45 0.45)
			(drill 0.1)
			(layers "*.Cu")
			(remove_unused_layers no)
			(net 1 "GND")
			(pinfunction "GND_EP")
			(pintype "power_in")
		)
		(pad "59" thru_hole circle
			(at -0.15 -1.321 180)
			(size 0.45 0.45)
			(drill 0.1)
			(layers "*.Cu")
			(remove_unused_layers no)
			(net 1 "GND")
			(pinfunction "GND_EP")
			(pintype "power_in")
		)
	)
)
